(kicad_pcb
	(version 20241229)
	(generator "pcbnew")
	(generator_version "9.0")
	(general
		(thickness 1.61)
		(legacy_teardrops no)
	)
	(paper "A3")
	(title_block
		(title "RDIMM DDR5 Tester")
		(date "2026-05-21")
		(rev "2.2.0")
		(company "Antmicro")
		(comment 9 "footprints 770-774 of 796")
	)
	(layers
		(0 "F.Cu" signal)
		(4 "In1.Cu" power)
		(6 "In2.Cu" mixed)
		(8 "In3.Cu" power)
		(10 "In4.Cu" mixed)
		(12 "In5.Cu" power)
		(14 "In6.Cu" mixed)
		(16 "In7.Cu" power)
		(18 "In8.Cu" power)
		(20 "In9.Cu" mixed)
		(22 "In10.Cu" power)
		(2 "B.Cu" signal)
		(9 "F.Adhes" user "F.Adhesive")
		(11 "B.Adhes" user "B.Adhesive")
		(13 "F.Paste" user)
		(15 "B.Paste" user)
		(5 "F.SilkS" user "F.Silkscreen")
		(7 "B.SilkS" user "B.Silkscreen")
		(1 "F.Mask" user)
		(3 "B.Mask" user)
		(17 "Dwgs.User" user "User.Drawings")
		(19 "Cmts.User" user "User.Comments")
		(21 "Eco1.User" user "User.Eco1")
		(23 "Eco2.User" user "User.Eco2")
		(25 "Edge.Cuts" user)
		(27 "Margin" user)
		(31 "F.CrtYd" user "F.Courtyard")
		(29 "B.CrtYd" user "B.Courtyard")
		(35 "F.Fab" user)
		(33 "B.Fab" user)
	)
	(footprint "antmicro-footprints:C_0402_1005Metric"
		(layer "B.Cu")
		(at 168.65 193.299501 -90)
		(descr "Capacitor SMD 0402")
		(tags "capacitor SMD 0402")
		(property "Reference" "C233"
			(at -3.859501 -0.43 90)
			(layer "B.SilkS")
			(effects
				(font
					(size 0.7 0.7)
					(thickness 0.15)
				)
				(justify left bottom mirror)
			)
		)
		(property "Value" "C_100n_0402"
			(at -1.022927 -2.155213 90)
			(layer "B.Fab")
			(effects
				(font
					(size 0.7 0.7)
					(thickness 0.15)
				)
				(justify left bottom mirror)
			)
		)
		(property "Datasheet" "https://www.murata.com/products/productdetail?partno=GRM155R61H104KE14%23"
			(at 0 0 270)
			(layer "F.Fab")
			(hide yes)
			(effects
				(font
					(size 1.27 1.27)
					(thickness 0.15)
				)
			)
		)
		(property "Manufacturer" "Murata"
			(at 0 0 270)
			(unlocked yes)
			(layer "B.Fab")
			(hide yes)
			(effects
				(font
					(size 1 1)
					(thickness 0.15)
				)
				(justify mirror)
			)
		)
		(property "MPN" "GRM155R61H104KE14D"
			(at 0 0 270)
			(unlocked yes)
			(layer "B.Fab")
			(hide yes)
			(effects
				(font
					(size 1 1)
					(thickness 0.15)
				)
				(justify mirror)
			)
		)
		(property "Val" "100n"
			(at 0 0 270)
			(unlocked yes)
			(layer "B.Fab")
			(hide yes)
			(effects
				(font
					(size 1 1)
					(thickness 0.15)
				)
				(justify mirror)
			)
		)
		(property "License" "Apache-2.0"
			(at 0 0 270)
			(unlocked yes)
			(layer "B.Fab")
			(hide yes)
			(effects
				(font
					(size 1 1)
					(thickness 0.15)
				)
				(justify mirror)
			)
		)
		(property "Author" "Antmicro"
			(at 0 0 270)
			(unlocked yes)
			(layer "B.Fab")
			(hide yes)
			(effects
				(font
					(size 1 1)
					(thickness 0.15)
				)
				(justify mirror)
			)
		)
		(property "Voltage" "50V"
			(at 0 0 270)
			(unlocked yes)
			(layer "B.Fab")
			(hide yes)
			(effects
				(font
					(size 1 1)
					(thickness 0.15)
				)
				(justify mirror)
			)
		)
		(property "Dielectric" "X5R"
			(at 0 0 270)
			(unlocked yes)
			(layer "B.Fab")
			(hide yes)
			(effects
				(font
					(size 1 1)
					(thickness 0.15)
				)
				(justify mirror)
			)
		)
		(sheetname "/FPGA MGT Interface/")
		(sheetfile "fpga-mgt.kicad_sch")
		(attr smd)
		(fp_rect
			(start -0.925 0.47)
			(end 0.925 -0.47)
			(stroke
				(width 0.05)
				(type default)
			)
			(fill no)
			(layer "B.CrtYd")
		)
		(fp_line
			(start -0.494 0.25)
			(end 0.504 0.25)
			(stroke
				(width 0.15)
				(type solid)
			)
			(layer "B.Fab")
		)
		(fp_line
			(start 0.504 0.25)
			(end 0.504 -0.248)
			(stroke
				(width 0.15)
				(type solid)
			)
			(layer "B.Fab")
		)
		(fp_line
			(start -0.494 -0.248)
			(end -0.494 0.25)
			(stroke
				(width 0.15)
				(type solid)
			)
			(layer "B.Fab")
		)
		(fp_line
			(start 0.504 -0.248)
			(end -0.494 -0.248)
			(stroke
				(width 0.15)
				(type solid)
			)
			(layer "B.Fab")
		)
		(fp_text user "${REFERENCE}"
			(at -0.939 -4.599 90)
			(layer "B.Fab")
			(effects
				(font
					(size 0.7 0.7)
					(thickness 0.15)
				)
				(justify left bottom mirror)
			)
		)
		(fp_text user "Author: Antmicro"
			(at -0.939 -3.399 90)
			(layer "B.Fab")
			(effects
				(font
					(size 0.7 0.7)
					(thickness 0.15)
				)
				(justify left bottom mirror)
			)
		)
		(fp_text user "License: Apache-2.0"
			(at -0.939 -5.799 90)
			(layer "B.Fab")
			(effects
				(font
					(size 0.7 0.7)
					(thickness 0.15)
				)
				(justify left bottom mirror)
			)
		)
		(pad "1" smd roundrect
			(at -0.48 0 270)
			(size 0.59 0.64)
			(layers "B.Cu" "B.Mask" "B.Paste")
			(roundrect_rratio 0.25)
			(net 29 "/FPGA MGT Interface/GTY_225_TX2_N")
			(pintype "passive")
		)
		(pad "2" smd roundrect
			(at 0.48 0 270)
			(size 0.59 0.64)
			(layers "B.Cu" "B.Mask" "B.Paste")
			(roundrect_rratio 0.25)
			(net 30 "/FPGA MGT Interface/PCIE.TXD1_N")
			(pintype "passive")
		)
	)
	(footprint "antmicro-footprints:R_0402_1005Metric"
		(layer "B.Cu")
		(at 205.23 136.0045)
		(descr "Resistor SMD 0402")
		(tags "resistor SMD 0402")
		(property "Reference" "R253"
			(at -0.03 -1.0045 0)
			(layer "B.SilkS")
			(effects
				(font
					(size 0.7 0.7)
					(thickness 0.15)
				)
				(justify mirror)
			)
		)
		(property "Value" "R_1k_0402"
			(at -1.011843 -1.772047 0)
			(layer "B.Fab")
			(effects
				(font
					(size 0.7 0.7)
					(thickness 0.15)
				)
				(justify right top mirror)
			)
		)
		(property "Datasheet" "https://www.bourns.com/docs/product-datasheets/cr.pdf"
			(at 0 0 0)
			(layer "B.Fab")
			(hide yes)
			(effects
				(font
					(size 1.27 1.27)
					(thickness 0.15)
				)
				(justify mirror)
			)
		)
		(property "MPN" "CR0402-FX-1001GLF"
			(at 0 0 180)
			(unlocked yes)
			(layer "B.Fab")
			(hide yes)
			(effects
				(font
					(size 1 1)
					(thickness 0.15)
				)
				(justify mirror)
			)
		)
		(property "Manufacturer" "Bourns"
			(at 0 0 180)
			(unlocked yes)
			(layer "B.Fab")
			(hide yes)
			(effects
				(font
					(size 1 1)
					(thickness 0.15)
				)
				(justify mirror)
			)
		)
		(property "License" "Apache-2.0"
			(at 0 0 180)
			(unlocked yes)
			(layer "B.Fab")
			(hide yes)
			(effects
				(font
					(size 1 1)
					(thickness 0.15)
				)
				(justify mirror)
			)
		)
		(property "Author" "Antmicro"
			(at 0 0 180)
			(unlocked yes)
			(layer "B.Fab")
			(hide yes)
			(effects
				(font
					(size 1 1)
					(thickness 0.15)
				)
				(justify mirror)
			)
		)
		(property "Val" "1k"
			(at 0 0 180)
			(unlocked yes)
			(layer "B.Fab")
			(hide yes)
			(effects
				(font
					(size 1 1)
					(thickness 0.15)
				)
				(justify mirror)
			)
		)
		(property "Tolerance" "1%"
			(at 0 0 180)
			(unlocked yes)
			(layer "B.Fab")
			(hide yes)
			(effects
				(font
					(size 1 1)
					(thickness 0.15)
				)
				(justify mirror)
			)
		)
		(sheetname "/FPGA banks HP/")
		(sheetfile "fpga-hp-banks.kicad_sch")
		(attr smd)
		(fp_rect
			(start -0.925 0.47)
			(end 0.925 -0.47)
			(stroke
				(width 0.05)
				(type default)
			)
			(fill no)
			(layer "B.CrtYd")
		)
		(fp_rect
			(start -0.5 0.25)
			(end 0.5 -0.25)
			(stroke
				(width 0.15)
				(type solid)
			)
			(fill no)
			(layer "B.Fab")
		)
		(fp_text user "License: Apache-2.0"
			(at -0.95 -5.169 0)
			(layer "B.Fab")
			(effects
				(font
					(size 0.7 0.7)
					(thickness 0.15)
				)
				(justify right top mirror)
			)
		)
		(fp_text user "Author: Antmicro"
			(at -0.95 -4.169 0)
			(layer "B.Fab")
			(effects
				(font
					(size 0.7 0.7)
					(thickness 0.15)
				)
				(justify right top mirror)
			)
		)
		(fp_text user "${REFERENCE}"
			(at -0.95 -3.168 0)
			(layer "B.Fab")
			(effects
				(font
					(size 0.7 0.7)
					(thickness 0.15)
				)
				(justify right top mirror)
			)
		)
		(pad "1" smd roundrect
			(at -0.48 0)
			(size 0.59 0.64)
			(layers "B.Cu" "B.Mask" "B.Paste")
			(roundrect_rratio 0.25)
			(net 827 "Net-(R253-Pad1)")
			(pintype "passive")
		)
		(pad "2" smd roundrect
			(at 0.48 0)
			(size 0.59 0.64)
			(layers "B.Cu" "B.Mask" "B.Paste")
			(roundrect_rratio 0.25)
			(net 687 "VDDQ")
			(pintype "passive")
		)
	)
	(footprint "antmicro-footprints:C_0402_1005Metric"
		(layer "B.Cu")
		(at 162.65 193.299501 90)
		(descr "Capacitor SMD 0402")
		(tags "capacitor SMD 0402")
		(property "Reference" "C229"
			(at 0.994 0.403501 90)
			(layer "B.SilkS")
			(effects
				(font
					(size 0.7 0.7)
					(thickness 0.15)
				)
				(justify right bottom mirror)
			)
		)
		(property "Value" "C_100n_0402"
			(at -1.022927 -2.155213 90)
			(layer "B.Fab")
			(effects
				(font
					(size 0.7 0.7)
					(thickness 0.15)
				)
				(justify right bottom mirror)
			)
		)
		(property "Datasheet" "https://www.murata.com/products/productdetail?partno=GRM155R61H104KE14%23"
			(at 0 0 90)
			(layer "F.Fab")
			(hide yes)
			(effects
				(font
					(size 1.27 1.27)
					(thickness 0.15)
				)
			)
		)
		(property "Manufacturer" "Murata"
			(at 0 0 90)
			(unlocked yes)
			(layer "B.Fab")
			(hide yes)
			(effects
				(font
					(size 1 1)
					(thickness 0.15)
				)
				(justify mirror)
			)
		)
		(property "MPN" "GRM155R61H104KE14D"
			(at 0 0 90)
			(unlocked yes)
			(layer "B.Fab")
			(hide yes)
			(effects
				(font
					(size 1 1)
					(thickness 0.15)
				)
				(justify mirror)
			)
		)
		(property "Val" "100n"
			(at 0 0 90)
			(unlocked yes)
			(layer "B.Fab")
			(hide yes)
			(effects
				(font
					(size 1 1)
					(thickness 0.15)
				)
				(justify mirror)
			)
		)
		(property "License" "Apache-2.0"
			(at 0 0 90)
			(unlocked yes)
			(layer "B.Fab")
			(hide yes)
			(effects
				(font
					(size 1 1)
					(thickness 0.15)
				)
				(justify mirror)
			)
		)
		(property "Author" "Antmicro"
			(at 0 0 90)
			(unlocked yes)
			(layer "B.Fab")
			(hide yes)
			(effects
				(font
					(size 1 1)
					(thickness 0.15)
				)
				(justify mirror)
			)
		)
		(property "Voltage" "50V"
			(at 0 0 90)
			(unlocked yes)
			(layer "B.Fab")
			(hide yes)
			(effects
				(font
					(size 1 1)
					(thickness 0.15)
				)
				(justify mirror)
			)
		)
		(property "Dielectric" "X5R"
			(at 0 0 90)
			(unlocked yes)
			(layer "B.Fab")
			(hide yes)
			(effects
				(font
					(size 1 1)
					(thickness 0.15)
				)
				(justify mirror)
			)
		)
		(sheetname "/FPGA MGT Interface/")
		(sheetfile "fpga-mgt.kicad_sch")
		(attr smd)
		(fp_rect
			(start -0.925 0.47)
			(end 0.925 -0.47)
			(stroke
				(width 0.05)
				(type default)
			)
			(fill no)
			(layer "B.CrtYd")
		)
		(fp_line
			(start 0.504 -0.248)
			(end -0.494 -0.248)
			(stroke
				(width 0.15)
				(type solid)
			)
			(layer "B.Fab")
		)
		(fp_line
			(start -0.494 -0.248)
			(end -0.494 0.25)
			(stroke
				(width 0.15)
				(type solid)
			)
			(layer "B.Fab")
		)
		(fp_line
			(start 0.504 0.25)
			(end 0.504 -0.248)
			(stroke
				(width 0.15)
				(type solid)
			)
			(layer "B.Fab")
		)
		(fp_line
			(start -0.494 0.25)
			(end 0.504 0.25)
			(stroke
				(width 0.15)
				(type solid)
			)
			(layer "B.Fab")
		)
		(fp_text user "Author: Antmicro"
			(at -0.939 -3.399 270)
			(layer "B.Fab")
			(effects
				(font
					(size 0.7 0.7)
					(thickness 0.15)
				)
				(justify left bottom mirror)
			)
		)
		(fp_text user "License: Apache-2.0"
			(at -0.939 -5.799 270)
			(layer "B.Fab")
			(effects
				(font
					(size 0.7 0.7)
					(thickness 0.15)
				)
				(justify left bottom mirror)
			)
		)
		(fp_text user "${REFERENCE}"
			(at -0.939 -4.599 270)
			(layer "B.Fab")
			(effects
				(font
					(size 0.7 0.7)
					(thickness 0.15)
				)
				(justify left bottom mirror)
			)
		)
		(pad "1" smd roundrect
			(at -0.48 0 90)
			(size 0.59 0.64)
			(layers "B.Cu" "B.Mask" "B.Paste")
			(roundrect_rratio 0.25)
			(net 21 "/FPGA MGT Interface/PCIE.TXD0_P")
			(pintype "passive")
		)
		(pad "2" smd roundrect
			(at 0.48 0 90)
			(size 0.59 0.64)
			(layers "B.Cu" "B.Mask" "B.Paste")
			(roundrect_rratio 0.25)
			(net 22 "/FPGA MGT Interface/GTY_225_TX3_P")
			(pintype "passive")
		)
	)
	(footprint "antmicro-footprints:R_0402_1005Metric"
		(layer "B.Cu")
		(at 132.63 174.35 -90)
		(descr "Resistor SMD 0402")
		(tags "resistor SMD 0402")
		(property "Reference" "R234"
			(at -3.8 -0.47 90)
			(layer "B.SilkS")
			(effects
				(font
					(size 0.7 0.7)
					(thickness 0.15)
				)
				(justify left bottom mirror)
			)
		)
		(property "Value" "R_2k2_0402"
			(at -1.011843 -1.772047 90)
			(layer "B.Fab")
			(effects
				(font
					(size 0.7 0.7)
					(thickness 0.15)
				)
				(justify left bottom mirror)
			)
		)
		(property "Datasheet" "https://www.bourns.com/docs/product-datasheets/cr.pdf"
			(at 0 0 270)
			(layer "F.Fab")
			(hide yes)
			(effects
				(font
					(size 1.27 1.27)
					(thickness 0.15)
				)
			)
		)
		(property "MPN" "CR0402-FX-2201GLF"
			(at 0 0 270)
			(unlocked yes)
			(layer "B.Fab")
			(hide yes)
			(effects
				(font
					(size 1 1)
					(thickness 0.15)
				)
				(justify mirror)
			)
		)
		(property "Manufacturer" "Bourns"
			(at 0 0 270)
			(unlocked yes)
			(layer "B.Fab")
			(hide yes)
			(effects
				(font
					(size 1 1)
					(thickness 0.15)
				)
				(justify mirror)
			)
		)
		(property "License" "Apache-2.0"
			(at 0 0 270)
			(unlocked yes)
			(layer "B.Fab")
			(hide yes)
			(effects
				(font
					(size 1 1)
					(thickness 0.15)
				)
				(justify mirror)
			)
		)
		(property "Author" "Antmicro"
			(at 0 0 270)
			(unlocked yes)
			(layer "B.Fab")
			(hide yes)
			(effects
				(font
					(size 1 1)
					(thickness 0.15)
				)
				(justify mirror)
			)
		)
		(property "Val" "2k2"
			(at 0 0 270)
			(unlocked yes)
			(layer "B.Fab")
			(hide yes)
			(effects
				(font
					(size 1 1)
					(thickness 0.15)
				)
				(justify mirror)
			)
		)
		(property "Tolerance" "1%"
			(at 0 0 270)
			(unlocked yes)
			(layer "B.Fab")
			(hide yes)
			(effects
				(font
					(size 1 1)
					(thickness 0.15)
				)
				(justify mirror)
			)
		)
		(property "Public" ""
			(at 0 0 270)
			(unlocked yes)
			(layer "B.Fab")
			(hide yes)
			(effects
				(font
					(size 1 1)
					(thickness 0.15)
				)
				(justify mirror)
			)
		)
		(sheetname "/HDMI + SD Card/")
		(sheetfile "hdmi-sd-card.kicad_sch")
		(attr smd)
		(fp_rect
			(start -0.925 0.47)
			(end 0.925 -0.47)
			(stroke
				(width 0.05)
				(type default)
			)
			(fill no)
			(layer "B.CrtYd")
		)
		(fp_rect
			(start -0.5 0.25)
			(end 0.5 -0.25)
			(stroke
				(width 0.15)
				(type solid)
			)
			(fill no)
			(layer "B.Fab")
		)
		(fp_text user "License: Apache-2.0"
			(at -0.95 -5.169 90)
			(layer "B.Fab")
			(effects
				(font
					(size 0.7 0.7)
					(thickness 0.15)
				)
				(justify left bottom mirror)
			)
		)
		(fp_text user "Author: Antmicro"
			(at -0.95 -4.169 90)
			(layer "B.Fab")
			(effects
				(font
					(size 0.7 0.7)
					(thickness 0.15)
				)
				(justify left bottom mirror)
			)
		)
		(fp_text user "${REFERENCE}"
			(at -0.95 -3.168 90)
			(layer "B.Fab")
			(effects
				(font
					(size 0.7 0.7)
					(thickness 0.15)
				)
				(justify left bottom mirror)
			)
		)
		(pad "1" smd roundrect
			(at -0.48 0 270)
			(size 0.59 0.64)
			(layers "B.Cu" "B.Mask" "B.Paste")
			(roundrect_rratio 0.25)
			(net 769 "/FPGA MGT Interface/HDMI_CTL.SDA")
			(pintype "passive")
		)
		(pad "2" smd roundrect
			(at 0.48 0 270)
			(size 0.59 0.64)
			(layers "B.Cu" "B.Mask" "B.Paste")
			(roundrect_rratio 0.25)
			(net 151 "+3V3")
			(pintype "passive")
		)
	)
	(footprint "antmicro-footprints:C_0402_1005Metric"
		(layer "B.Cu")
		(at 115.413499 118.149)
		(descr "Capacitor SMD 0402")
		(tags "capacitor SMD 0402")
		(property "Reference" "C234"
			(at 1.286501 0.151 0)
			(layer "B.SilkS")
			(effects
				(font
					(size 0.7 0.7)
					(thickness 0.15)
				)
				(justify right bottom mirror)
			)
		)
		(property "Value" "C_100n_0402"
			(at -1.022927 -2.155213 0)
			(layer "B.Fab")
			(effects
				(font
					(size 0.7 0.7)
					(thickness 0.15)
				)
				(justify right bottom mirror)
			)
		)
		(property "Datasheet" "https://www.murata.com/products/productdetail?partno=GRM155R61H104KE14%23"
			(at 0 0 0)
			(layer "F.Fab")
			(hide yes)
			(effects
				(font
					(size 1.27 1.27)
					(thickness 0.15)
				)
			)
		)
		(property "Manufacturer" "Murata"
			(at 0 0 0)
			(unlocked yes)
			(layer "B.Fab")
			(hide yes)
			(effects
				(font
					(size 1 1)
					(thickness 0.15)
				)
				(justify mirror)
			)
		)
		(property "MPN" "GRM155R61H104KE14D"
			(at 0 0 0)
			(unlocked yes)
			(layer "B.Fab")
			(hide yes)
			(effects
				(font
					(size 1 1)
					(thickness 0.15)
				)
				(justify mirror)
			)
		)
		(property "Val" "100n"
			(at 0 0 0)
			(unlocked yes)
			(layer "B.Fab")
			(hide yes)
			(effects
				(font
					(size 1 1)
					(thickness 0.15)
				)
				(justify mirror)
			)
		)
		(property "License" "Apache-2.0"
			(at 0 0 0)
			(unlocked yes)
			(layer "B.Fab")
			(hide yes)
			(effects
				(font
					(size 1 1)
					(thickness 0.15)
				)
				(justify mirror)
			)
		)
		(property "Author" "Antmicro"
			(at 0 0 0)
			(unlocked yes)
			(layer "B.Fab")
			(hide yes)
			(effects
				(font
					(size 1 1)
					(thickness 0.15)
				)
				(justify mirror)
			)
		)
		(property "Voltage" "50V"
			(at 0 0 0)
			(unlocked yes)
			(layer "B.Fab")
			(hide yes)
			(effects
				(font
					(size 1 1)
					(thickness 0.15)
				)
				(justify mirror)
			)
		)
		(property "Dielectric" "X5R"
			(at 0 0 0)
			(unlocked yes)
			(layer "B.Fab")
			(hide yes)
			(effects
				(font
					(size 1 1)
					(thickness 0.15)
				)
				(justify mirror)
			)
		)
		(sheetname "/Ethernet/")
		(sheetfile "ethernet.kicad_sch")
		(attr smd)
		(fp_rect
			(start -0.925 0.47)
			(end 0.925 -0.47)
			(stroke
				(width 0.05)
				(type default)
			)
			(fill no)
			(layer "B.CrtYd")
		)
		(fp_line
			(start -0.494 -0.248)
			(end -0.494 0.25)
			(stroke
				(width 0.15)
				(type solid)
			)
			(layer "B.Fab")
		)
		(fp_line
			(start -0.494 0.25)
			(end 0.504 0.25)
			(stroke
				(width 0.15)
				(type solid)
			)
			(layer "B.Fab")
		)
		(fp_line
			(start 0.504 -0.248)
			(end -0.494 -0.248)
			(stroke
				(width 0.15)
				(type solid)
			)
			(layer "B.Fab")
		)
		(fp_line
			(start 0.504 0.25)
			(end 0.504 -0.248)
			(stroke
				(width 0.15)
				(type solid)
			)
			(layer "B.Fab")
		)
		(fp_text user "License: Apache-2.0"
			(at -0.939 -5.799 180)
			(layer "B.Fab")
			(effects
				(font
					(size 0.7 0.7)
					(thickness 0.15)
				)
				(justify left bottom mirror)
			)
		)
		(fp_text user "${REFERENCE}"
			(at -0.939 -4.599 180)
			(layer "B.Fab")
			(effects
				(font
					(size 0.7 0.7)
					(thickness 0.15)
				)
				(justify left bottom mirror)
			)
		)
		(fp_text user "Author: Antmicro"
			(at -0.939 -3.399 180)
			(layer "B.Fab")
			(effects
				(font
					(size 0.7 0.7)
					(thickness 0.15)
				)
				(justify left bottom mirror)
			)
		)
		(pad "1" smd roundrect
			(at -0.48 0)
			(size 0.59 0.64)
			(layers "B.Cu" "B.Mask" "B.Paste")
			(roundrect_rratio 0.25)
			(net 31 "Net-(C234-Pad1)")
			(pintype "passive")
		)
		(pad "2" smd roundrect
			(at 0.48 0)
			(size 0.59 0.64)
			(layers "B.Cu" "B.Mask" "B.Paste")
			(roundrect_rratio 0.25)
			(net 1 "GND")
			(pintype "passive")
		)
	)
)
